# T6G (Grand Teton) — schematic netlist excerpt (pin names and nets, part order shuffled) for the footprints in the layout excerpt that follows; sources: Cadence DE-HDL packaged netlist, KiCad conversion of 04192023_DAF0TMB3IC0_F0TG_MB_C_brd_V02_OCP.brd

R6038  Q_RES  0 5% CHIP  pkg 0402LF  page 80 : A = UV_ALERT_N ; B = IRQ_UV_DETECT_N
C672  Q_CAP  4.7UF 6.3V 20% X6S  pkg 0402  page 301 : A = P1V8_CPU0_RT_1D ; B = GND

(kicad_pcb
	(version 20260206)
	(generator "pcbnew")
	(generator_version "10.0")
	(general
		(thickness 1.6)
		(legacy_teardrops no)
	)
	(paper "A4")
	(title_block
		(title "04192023_DAF0TMB3IC0_F0TG_MB_C_brd_V02_OCP.brd")
		(comment 1 "Grand Teton / footprints 3264-3265 of 8354")
	)
	(layers
		(0 "F.Cu" signal "TOP")
		(4 "In1.Cu" signal "GND")
		(6 "In2.Cu" signal "IN1")
		(8 "In3.Cu" signal "GND1")
		(10 "In4.Cu" signal "IN2")
		(12 "In5.Cu" signal "GND2")
		(14 "In6.Cu" signal "IN3")
		(16 "In7.Cu" signal "GND3")
		(18 "In8.Cu" signal "VCC")
		(20 "In9.Cu" signal "VCC1")
		(22 "In10.Cu" signal "GND4")
		(24 "In11.Cu" signal "IN4")
		(26 "In12.Cu" signal "GND5")
		(28 "In13.Cu" signal "IN5")
		(30 "In14.Cu" signal "GND6")
		(32 "In15.Cu" signal "IN6")
		(34 "In16.Cu" signal "GND7")
		(2 "B.Cu" signal "BOTTOM")
		(9 "F.Adhes" user "F.Adhesive")
		(11 "B.Adhes" user "B.Adhesive")
		(13 "F.Paste" user "Package Geometry/Pastemask Top")
		(15 "B.Paste" user "Package Geometry/Pastemask Bottom")
		(5 "F.SilkS" user "Ref Des/Silkscreen Top")
		(7 "B.SilkS" user "Ref Des/Silkscreen Bottom")
		(1 "F.Mask" user "Board Geometry/Soldermask Top")
		(3 "B.Mask" user "Board Geometry/Soldermask Bottom")
		(17 "Dwgs.User" user "User.Drawings")
		(19 "Cmts.User" user "User.Comments")
		(21 "Eco1.User" user "User.Eco1")
		(23 "Eco2.User" user "User.Eco2")
		(25 "Edge.Cuts" user "Board Geometry/Outline")
		(27 "Margin" user)
		(31 "F.CrtYd" user "Package Geometry/Place Bound Top")
		(29 "B.CrtYd" user "Package Geometry/Place Bound Bottom")
		(35 "F.Fab" user "Ref Des/Assembly Top")
		(33 "B.Fab" user "Ref Des/Assembly Bottom")
	)
	(footprint ""
		(layer "F.Cu")
		(at 163.703 -115.280948 180)
		(property "Reference" "R6038"
			(at 0 0 180)
			(layer "F.SilkS")
			(hide yes)
			(effects
				(font
					(size 1.27 1.27)
				)
			)
		)
		(property "Value" ""
			(at 0 0 180)
			(layer "F.Fab")
			(effects
				(font
					(size 1.27 1.27)
				)
			)
		)
		(duplicate_pad_numbers_are_jumpers no)
		(fp_line
			(start 0.7874 0.4064)
			(end -0.7874 0.4064)
			(stroke
				(width 0.1524)
				(type default)
			)
			(layer "F.SilkS")
		)
		(fp_line
			(start 0.7874 -0.4064)
			(end 0.7874 0.4064)
			(stroke
				(width 0.1524)
				(type default)
			)
			(layer "F.SilkS")
		)
		(fp_line
			(start -0.7874 0.4064)
			(end -0.7874 -0.4064)
			(stroke
				(width 0.1524)
				(type default)
			)
			(layer "F.SilkS")
		)
		(fp_line
			(start -0.7874 -0.4064)
			(end 0.7874 -0.4064)
			(stroke
				(width 0.1524)
				(type default)
			)
			(layer "F.SilkS")
		)
		(fp_line
			(start 0.67945 0.3048)
			(end 0.120396 0.3048)
			(stroke
				(width 0.1)
				(type default)
			)
			(layer "F.Fab")
		)
		(fp_line
			(start 0.67945 -0.3048)
			(end 0.67945 0.3048)
			(stroke
				(width 0.1)
				(type default)
			)
			(layer "F.Fab")
		)
		(fp_line
			(start 0.12065 -0.2794)
			(end 0.12065 -0.3048)
			(stroke
				(width 0.1)
				(type default)
			)
			(layer "F.Fab")
		)
		(fp_line
			(start 0.12065 -0.3048)
			(end 0.67945 -0.3048)
			(stroke
				(width 0.1)
				(type default)
			)
			(layer "F.Fab")
		)
		(fp_line
			(start 0.120396 0.3048)
			(end 0.120396 0.2794)
			(stroke
				(width 0.1)
				(type default)
			)
			(layer "F.Fab")
		)
		(fp_line
			(start 0.120396 0.2794)
			(end -0.12065 0.2794)
			(stroke
				(width 0.1)
				(type default)
			)
			(layer "F.Fab")
		)
		(fp_line
			(start -0.12065 0.3048)
			(end -0.67945 0.3048)
			(stroke
				(width 0.1)
				(type default)
			)
			(layer "F.Fab")
		)
		(fp_line
			(start -0.12065 0.2794)
			(end -0.12065 0.3048)
			(stroke
				(width 0.1)
				(type default)
			)
			(layer "F.Fab")
		)
		(fp_line
			(start -0.12065 -0.2794)
			(end 0.12065 -0.2794)
			(stroke
				(width 0.1)
				(type default)
			)
			(layer "F.Fab")
		)
		(fp_line
			(start -0.12065 -0.305054)
			(end -0.12065 -0.2794)
			(stroke
				(width 0.1)
				(type default)
			)
			(layer "F.Fab")
		)
		(fp_line
			(start -0.67945 0.3048)
			(end -0.67945 -0.305054)
			(stroke
				(width 0.1)
				(type default)
			)
			(layer "F.Fab")
		)
		(fp_line
			(start -0.67945 -0.305054)
			(end -0.12065 -0.305054)
			(stroke
				(width 0.1)
				(type default)
			)
			(layer "F.Fab")
		)
		(pad "1" smd circle
			(at -0.40005 0 180)
			(size 0 0)
			(layers "F.Cu" "F.Mask" "F.Paste")
			(net "UV_ALERT_N")
		)
		(pad "2" smd circle
			(at 0.40005 0 180)
			(size 0 0)
			(layers "F.Cu" "F.Mask" "F.Paste")
			(net "IRQ_UV_DETECT_N")
		)
	)
	(footprint ""
		(layer "F.Cu")
		(at 429.171354 -396.119604)
		(property "Reference" "C672"
			(at 0 0 0)
			(layer "F.SilkS")
			(hide yes)
			(effects
				(font
					(size 1.27 1.27)
				)
			)
		)
		(property "Value" ""
			(at 0 0 0)
			(layer "F.Fab")
			(effects
				(font
					(size 1.27 1.27)
				)
			)
		)
		(duplicate_pad_numbers_are_jumpers no)
		(fp_line
			(start -0.7874 -0.4064)
			(end 0.7874 -0.4064)
			(stroke
				(width 0.1524)
				(type default)
			)
			(layer "F.SilkS")
		)
		(fp_line
			(start -0.7874 0.4064)
			(end -0.7874 -0.4064)
			(stroke
				(width 0.1524)
				(type default)
			)
			(layer "F.SilkS")
		)
		(fp_line
			(start 0.7874 -0.4064)
			(end 0.7874 0.4064)
			(stroke
				(width 0.1524)
				(type default)
			)
			(layer "F.SilkS")
		)
		(fp_line
			(start 0.7874 0.4064)
			(end -0.7874 0.4064)
			(stroke
				(width 0.1524)
				(type default)
			)
			(layer "F.SilkS")
		)
		(fp_line
			(start -0.67945 -0.305054)
			(end -0.12065 -0.305054)
			(stroke
				(width 0.1)
				(type default)
			)
			(layer "F.Fab")
		)
		(fp_line
			(start -0.67945 0.3048)
			(end -0.67945 -0.305054)
			(stroke
				(width 0.1)
				(type default)
			)
			(layer "F.Fab")
		)
		(fp_line
			(start -0.12065 -0.305054)
			(end -0.12065 -0.2794)
			(stroke
				(width 0.1)
				(type default)
			)
			(layer "F.Fab")
		)
		(fp_line
			(start -0.12065 -0.2794)
			(end 0.12065 -0.2794)
			(stroke
				(width 0.1)
				(type default)
			)
			(layer "F.Fab")
		)
		(fp_line
			(start -0.12065 0.2794)
			(end -0.12065 0.3048)
			(stroke
				(width 0.1)
				(type default)
			)
			(layer "F.Fab")
		)
		(fp_line
			(start -0.12065 0.3048)
			(end -0.67945 0.3048)
			(stroke
				(width 0.1)
				(type default)
			)
			(layer "F.Fab")
		)
		(fp_line
			(start 0.120396 0.2794)
			(end -0.12065 0.2794)
			(stroke
				(width 0.1)
				(type default)
			)
			(layer "F.Fab")
		)
		(fp_line
			(start 0.120396 0.3048)
			(end 0.120396 0.2794)
			(stroke
				(width 0.1)
				(type default)
			)
			(layer "F.Fab")
		)
		(fp_line
			(start 0.12065 -0.3048)
			(end 0.67945 -0.3048)
			(stroke
				(width 0.1)
				(type default)
			)
			(layer "F.Fab")
		)
		(fp_line
			(start 0.12065 -0.2794)
			(end 0.12065 -0.3048)
			(stroke
				(width 0.1)
				(type default)
			)
			(layer "F.Fab")
		)
		(fp_line
			(start 0.67945 -0.3048)
			(end 0.67945 0.3048)
			(stroke
				(width 0.1)
				(type default)
			)
			(layer "F.Fab")
		)
		(fp_line
			(start 0.67945 0.3048)
			(end 0.120396 0.3048)
			(stroke
				(width 0.1)
				(type default)
			)
			(layer "F.Fab")
		)
		(pad "1" smd circle
			(at -0.40005 0)
			(size 0 0)
			(layers "F.Cu" "F.Mask" "F.Paste")
			(net "P1V8_CPU0_RT_1D")
		)
		(pad "2" smd circle
			(at 0.40005 0)
			(size 0 0)
			(layers "F.Cu" "F.Mask" "F.Paste")
			(net "GND")
		)
	)
)
